# S9S_MB_2U (Grand Teton) — schematic netlist excerpt (pin names and nets, part order shuffled) for the footprints in the layout excerpt that follows; sources: Cadence DE-HDL packaged netlist, KiCad conversion of 03242023_DA0F0TMBIJ0_F0T_Motherboard_J_brd_V01_OCP.brd

R4095  Q_RES  10K 1% CHIP  pkg 0402LF  page 183 : A = PD_PCH_GPPC_A_19 ; B = GND
PC1181_P0_3  Q_CAP  22UF 16V 20% X6S  pkg C0805  page 272 : A = SW_P12V_PVCCFA_EHV_FIVRA_CPU0_R ; B = GND
R3826  Q_RES  100K 1% CHIP  pkg 0402LF  page 162 : A = P3V3_AUX ; B = OCP_V3_2_P3V3_PWRGD

(kicad_pcb
	(version 20260206)
	(generator "pcbnew")
	(generator_version "10.0")
	(general
		(thickness 1.6)
		(legacy_teardrops no)
	)
	(paper "A4")
	(title_block
		(title "03242023_DA0F0TMBIJ0_F0T_Motherboard_J_brd_V01_OCP.brd")
		(comment 1 "Grand Teton / footprints 4756-4758 of 6105")
	)
	(layers
		(0 "F.Cu" signal "TOP")
		(4 "In1.Cu" signal "GND")
		(6 "In2.Cu" signal "IN1")
		(8 "In3.Cu" signal "GND1")
		(10 "In4.Cu" signal "IN2")
		(12 "In5.Cu" signal "GND2")
		(14 "In6.Cu" signal "IN3")
		(16 "In7.Cu" signal "GND3")
		(18 "In8.Cu" signal "VCC")
		(20 "In9.Cu" signal "VCC1")
		(22 "In10.Cu" signal "GND4")
		(24 "In11.Cu" signal "IN4")
		(26 "In12.Cu" signal "GND5")
		(28 "In13.Cu" signal "IN5")
		(30 "In14.Cu" signal "GND6")
		(32 "In15.Cu" signal "IN6")
		(34 "In16.Cu" signal "GND7")
		(2 "B.Cu" signal "BOTTOM")
		(9 "F.Adhes" user "F.Adhesive")
		(11 "B.Adhes" user "B.Adhesive")
		(13 "F.Paste" user "Package Geometry/Pastemask Top")
		(15 "B.Paste" user "Package Geometry/Pastemask Bottom")
		(5 "F.SilkS" user "Ref Des/Silkscreen Top")
		(7 "B.SilkS" user "Ref Des/Silkscreen Bottom")
		(1 "F.Mask" user "Board Geometry/Soldermask Top")
		(3 "B.Mask" user "Board Geometry/Soldermask Bottom")
		(17 "Dwgs.User" user "User.Drawings")
		(19 "Cmts.User" user "User.Comments")
		(21 "Eco1.User" user "User.Eco1")
		(23 "Eco2.User" user "User.Eco2")
		(25 "Edge.Cuts" user "Board Geometry/Outline")
		(27 "Margin" user)
		(31 "F.CrtYd" user "Package Geometry/Place Bound Top")
		(29 "B.CrtYd" user "Package Geometry/Place Bound Bottom")
		(35 "F.Fab" user "Ref Des/Assembly Top")
		(33 "B.Fab" user "Ref Des/Assembly Bottom")
	)
	(footprint ""
		(layer "B.Cu")
		(at 331.01788 -27.701748 90)
		(property "Reference" "R4095"
			(at 0 0 90)
			(layer "B.SilkS")
			(hide yes)
			(effects
				(font
					(size 1.27 1.27)
				)
				(justify mirror)
			)
		)
		(property "Value" ""
			(at 0 0 90)
			(layer "B.Fab")
			(effects
				(font
					(size 1.27 1.27)
				)
				(justify mirror)
			)
		)
		(duplicate_pad_numbers_are_jumpers no)
		(fp_line
			(start 0.7874 -0.4064)
			(end -0.7874 -0.4064)
			(stroke
				(width 0.1524)
				(type default)
			)
			(layer "B.SilkS")
		)
		(fp_line
			(start -0.7874 -0.4064)
			(end -0.7874 0.4064)
			(stroke
				(width 0.1524)
				(type default)
			)
			(layer "B.SilkS")
		)
		(fp_line
			(start 0.7874 0.4064)
			(end 0.7874 -0.4064)
			(stroke
				(width 0.1524)
				(type default)
			)
			(layer "B.SilkS")
		)
		(fp_line
			(start -0.7874 0.4064)
			(end 0.7874 0.4064)
			(stroke
				(width 0.1524)
				(type default)
			)
			(layer "B.SilkS")
		)
		(fp_line
			(start 0.67945 -0.305054)
			(end 0.12065 -0.305054)
			(stroke
				(width 0.1)
				(type default)
			)
			(layer "B.Fab")
		)
		(fp_line
			(start 0.12065 -0.305054)
			(end 0.12065 -0.2794)
			(stroke
				(width 0.1)
				(type default)
			)
			(layer "B.Fab")
		)
		(fp_line
			(start -0.12065 -0.3048)
			(end -0.67945 -0.3048)
			(stroke
				(width 0.1)
				(type default)
			)
			(layer "B.Fab")
		)
		(fp_line
			(start -0.67945 -0.3048)
			(end -0.67945 0.3048)
			(stroke
				(width 0.1)
				(type default)
			)
			(layer "B.Fab")
		)
		(fp_line
			(start 0.12065 -0.2794)
			(end -0.12065 -0.2794)
			(stroke
				(width 0.1)
				(type default)
			)
			(layer "B.Fab")
		)
		(fp_line
			(start -0.12065 -0.2794)
			(end -0.12065 -0.3048)
			(stroke
				(width 0.1)
				(type default)
			)
			(layer "B.Fab")
		)
		(fp_line
			(start 0.12065 0.2794)
			(end 0.12065 0.3048)
			(stroke
				(width 0.1)
				(type default)
			)
			(layer "B.Fab")
		)
		(fp_line
			(start -0.120396 0.2794)
			(end 0.12065 0.2794)
			(stroke
				(width 0.1)
				(type default)
			)
			(layer "B.Fab")
		)
		(fp_line
			(start 0.67945 0.3048)
			(end 0.67945 -0.305054)
			(stroke
				(width 0.1)
				(type default)
			)
			(layer "B.Fab")
		)
		(fp_line
			(start 0.12065 0.3048)
			(end 0.67945 0.3048)
			(stroke
				(width 0.1)
				(type default)
			)
			(layer "B.Fab")
		)
		(fp_line
			(start -0.120396 0.3048)
			(end -0.120396 0.2794)
			(stroke
				(width 0.1)
				(type default)
			)
			(layer "B.Fab")
		)
		(fp_line
			(start -0.67945 0.3048)
			(end -0.120396 0.3048)
			(stroke
				(width 0.1)
				(type default)
			)
			(layer "B.Fab")
		)
		(pad "1" smd circle
			(at 0.40005 0 270)
			(size 0 0)
			(layers "B.Cu" "B.Mask" "B.Paste")
			(net "PD_PCH_GPPC_A_19")
		)
		(pad "2" smd circle
			(at -0.40005 0 270)
			(size 0 0)
			(layers "B.Cu" "B.Mask" "B.Paste")
			(net "GND")
		)
	)
	(footprint ""
		(layer "B.Cu")
		(at 426.970444 -362.107226 90)
		(property "Reference" "PC1181_P0_3"
			(at 0 0 90)
			(layer "B.SilkS")
			(hide yes)
			(effects
				(font
					(size 1.27 1.27)
				)
				(justify mirror)
			)
		)
		(property "Value" ""
			(at 0 0 90)
			(layer "B.Fab")
			(effects
				(font
					(size 1.27 1.27)
				)
				(justify mirror)
			)
		)
		(duplicate_pad_numbers_are_jumpers no)
		(fp_line
			(start 1.524 -0.762)
			(end -1.524 -0.762)
			(stroke
				(width 0.1524)
				(type default)
			)
			(layer "B.SilkS")
		)
		(fp_line
			(start -1.524 -0.762)
			(end -1.524 0.762)
			(stroke
				(width 0.1524)
				(type default)
			)
			(layer "B.SilkS")
		)
		(fp_line
			(start 1.524 0.762)
			(end 1.524 -0.762)
			(stroke
				(width 0.1524)
				(type default)
			)
			(layer "B.SilkS")
		)
		(fp_line
			(start -1.524 0.762)
			(end 1.524 0.762)
			(stroke
				(width 0.1524)
				(type default)
			)
			(layer "B.SilkS")
		)
		(fp_line
			(start 1.1049 -0.724916)
			(end 1.1049 0.724916)
			(stroke
				(width 0.1)
				(type default)
			)
			(layer "B.Fab")
		)
		(fp_line
			(start -1.1049 -0.724916)
			(end 1.1049 -0.724916)
			(stroke
				(width 0.1)
				(type default)
			)
			(layer "B.Fab")
		)
		(fp_line
			(start 1.1049 0.724916)
			(end -1.1049 0.724916)
			(stroke
				(width 0.1)
				(type default)
			)
			(layer "B.Fab")
		)
		(fp_line
			(start -1.1049 0.724916)
			(end -1.1049 -0.724916)
			(stroke
				(width 0.1)
				(type default)
			)
			(layer "B.Fab")
		)
		(pad "1" smd rect
			(at 0.889 0 90)
			(size 1.016 1.27)
			(layers "B.Cu" "B.Mask" "B.Paste")
			(net "SW_P12V_PVCCFA_EHV_FIVRA_CPU0_R")
		)
		(pad "2" smd rect
			(at -0.889 0 90)
			(size 1.016 1.27)
			(layers "B.Cu" "B.Mask" "B.Paste")
			(net "GND")
		)
	)
	(footprint ""
		(layer "B.Cu")
		(at 81.74863 -52.082446)
		(property "Reference" "R3826"
			(at 0 0 0)
			(layer "B.SilkS")
			(hide yes)
			(effects
				(font
					(size 1.27 1.27)
				)
				(justify mirror)
			)
		)
		(property "Value" ""
			(at 0 0 0)
			(layer "B.Fab")
			(effects
				(font
					(size 1.27 1.27)
				)
				(justify mirror)
			)
		)
		(duplicate_pad_numbers_are_jumpers no)
		(fp_line
			(start -0.7874 -0.4064)
			(end -0.7874 0.4064)
			(stroke
				(width 0.1524)
				(type default)
			)
			(layer "B.SilkS")
		)
		(fp_line
			(start -0.7874 0.4064)
			(end 0.7874 0.4064)
			(stroke
				(width 0.1524)
				(type default)
			)
			(layer "B.SilkS")
		)
		(fp_line
			(start 0.7874 -0.4064)
			(end -0.7874 -0.4064)
			(stroke
				(width 0.1524)
				(type default)
			)
			(layer "B.SilkS")
		)
		(fp_line
			(start 0.7874 0.4064)
			(end 0.7874 -0.4064)
			(stroke
				(width 0.1524)
				(type default)
			)
			(layer "B.SilkS")
		)
		(fp_line
			(start -0.67945 -0.3048)
			(end -0.67945 0.3048)
			(stroke
				(width 0.1)
				(type default)
			)
			(layer "B.Fab")
		)
		(fp_line
			(start -0.67945 0.3048)
			(end -0.120396 0.3048)
			(stroke
				(width 0.1)
				(type default)
			)
			(layer "B.Fab")
		)
		(fp_line
			(start -0.12065 -0.3048)
			(end -0.67945 -0.3048)
			(stroke
				(width 0.1)
				(type default)
			)
			(layer "B.Fab")
		)
		(fp_line
			(start -0.12065 -0.2794)
			(end -0.12065 -0.3048)
			(stroke
				(width 0.1)
				(type default)
			)
			(layer "B.Fab")
		)
		(fp_line
			(start -0.120396 0.2794)
			(end 0.12065 0.2794)
			(stroke
				(width 0.1)
				(type default)
			)
			(layer "B.Fab")
		)
		(fp_line
			(start -0.120396 0.3048)
			(end -0.120396 0.2794)
			(stroke
				(width 0.1)
				(type default)
			)
			(layer "B.Fab")
		)
		(fp_line
			(start 0.12065 -0.305054)
			(end 0.12065 -0.2794)
			(stroke
				(width 0.1)
				(type default)
			)
			(layer "B.Fab")
		)
		(fp_line
			(start 0.12065 -0.2794)
			(end -0.12065 -0.2794)
			(stroke
				(width 0.1)
				(type default)
			)
			(layer "B.Fab")
		)
		(fp_line
			(start 0.12065 0.2794)
			(end 0.12065 0.3048)
			(stroke
				(width 0.1)
				(type default)
			)
			(layer "B.Fab")
		)
		(fp_line
			(start 0.12065 0.3048)
			(end 0.67945 0.3048)
			(stroke
				(width 0.1)
				(type default)
			)
			(layer "B.Fab")
		)
		(fp_line
			(start 0.67945 -0.305054)
			(end 0.12065 -0.305054)
			(stroke
				(width 0.1)
				(type default)
			)
			(layer "B.Fab")
		)
		(fp_line
			(start 0.67945 0.3048)
			(end 0.67945 -0.305054)
			(stroke
				(width 0.1)
				(type default)
			)
			(layer "B.Fab")
		)
		(pad "1" smd circle
			(at 0.40005 0 180)
			(size 0 0)
			(layers "B.Cu" "B.Mask" "B.Paste")
			(net "P3V3_AUX")
		)
		(pad "2" smd circle
			(at -0.40005 0 180)
			(size 0 0)
			(layers "B.Cu" "B.Mask" "B.Paste")
			(net "OCP_V3_2_P3V3_PWRGD")
		)
	)
)
